(kicad_pcb
	(version 20260206)
	(generator "pcbnew")
	(generator_version "10.0")
	(general
		(thickness 1.6)
		(legacy_teardrops no)
	)
	(paper "A4")
	(title_block
		(title "03242023_DA0F0TMBIJ0_F0T_Motherboard_J_brd_V01_OCP.brd")
		(comment 1 "Grand Teton / footprints 4669-4675 of 6105")
	)
	(layers
		(0 "F.Cu" signal "TOP")
		(4 "In1.Cu" signal "GND")
		(6 "In2.Cu" signal "IN1")
		(8 "In3.Cu" signal "GND1")
		(10 "In4.Cu" signal "IN2")
		(12 "In5.Cu" signal "GND2")
		(14 "In6.Cu" signal "IN3")
		(16 "In7.Cu" signal "GND3")
		(18 "In8.Cu" signal "VCC")
		(20 "In9.Cu" signal "VCC1")
		(22 "In10.Cu" signal "GND4")
		(24 "In11.Cu" signal "IN4")
		(26 "In12.Cu" signal "GND5")
		(28 "In13.Cu" signal "IN5")
		(30 "In14.Cu" signal "GND6")
		(32 "In15.Cu" signal "IN6")
		(34 "In16.Cu" signal "GND7")
		(2 "B.Cu" signal "BOTTOM")
		(9 "F.Adhes" user "F.Adhesive")
		(11 "B.Adhes" user "B.Adhesive")
		(13 "F.Paste" user "Package Geometry/Pastemask Top")
		(15 "B.Paste" user "Package Geometry/Pastemask Bottom")
		(5 "F.SilkS" user "Ref Des/Silkscreen Top")
		(7 "B.SilkS" user "Ref Des/Silkscreen Bottom")
		(1 "F.Mask" user "Board Geometry/Soldermask Top")
		(3 "B.Mask" user "Board Geometry/Soldermask Bottom")
		(17 "Dwgs.User" user "User.Drawings")
		(19 "Cmts.User" user "User.Comments")
		(21 "Eco1.User" user "User.Eco1")
		(23 "Eco2.User" user "User.Eco2")
		(25 "Edge.Cuts" user "Board Geometry/Outline")
		(27 "Margin" user)
		(31 "F.CrtYd" user "Package Geometry/Place Bound Top")
		(29 "B.CrtYd" user "Package Geometry/Place Bound Bottom")
		(35 "F.Fab" user "Ref Des/Assembly Top")
		(33 "B.Fab" user "Ref Des/Assembly Bottom")
	)
	(footprint ""
		(layer "B.Cu")
		(at 335.915254 -46.888146 -90)
		(property "Reference" "C1210"
			(at 0 0 90)
			(layer "B.SilkS")
			(hide yes)
			(effects
				(font
					(size 1.27 1.27)
				)
				(justify mirror)
			)
		)
		(property "Value" ""
			(at 0 0 90)
			(layer "B.Fab")
			(effects
				(font
					(size 1.27 1.27)
				)
				(justify mirror)
			)
		)
		(duplicate_pad_numbers_are_jumpers no)
		(fp_line
			(start -0.7874 0.4064)
			(end 0.7874 0.4064)
			(stroke
				(width 0.1524)
				(type default)
			)
			(layer "B.SilkS")
		)
		(fp_line
			(start 0.7874 0.4064)
			(end 0.7874 -0.4064)
			(stroke
				(width 0.1524)
				(type default)
			)
			(layer "B.SilkS")
		)
		(fp_line
			(start -0.7874 -0.4064)
			(end -0.7874 0.4064)
			(stroke
				(width 0.1524)
				(type default)
			)
			(layer "B.SilkS")
		)
		(fp_line
			(start 0.7874 -0.4064)
			(end -0.7874 -0.4064)
			(stroke
				(width 0.1524)
				(type default)
			)
			(layer "B.SilkS")
		)
		(fp_line
			(start -0.67945 0.3048)
			(end -0.120396 0.3048)
			(stroke
				(width 0.1)
				(type default)
			)
			(layer "B.Fab")
		)
		(fp_line
			(start -0.120396 0.3048)
			(end -0.120396 0.2794)
			(stroke
				(width 0.1)
				(type default)
			)
			(layer "B.Fab")
		)
		(fp_line
			(start 0.12065 0.3048)
			(end 0.67945 0.3048)
			(stroke
				(width 0.1)
				(type default)
			)
			(layer "B.Fab")
		)
		(fp_line
			(start 0.67945 0.3048)
			(end 0.67945 -0.305054)
			(stroke
				(width 0.1)
				(type default)
			)
			(layer "B.Fab")
		)
		(fp_line
			(start -0.120396 0.2794)
			(end 0.12065 0.2794)
			(stroke
				(width 0.1)
				(type default)
			)
			(layer "B.Fab")
		)
		(fp_line
			(start 0.12065 0.2794)
			(end 0.12065 0.3048)
			(stroke
				(width 0.1)
				(type default)
			)
			(layer "B.Fab")
		)
		(fp_line
			(start -0.12065 -0.2794)
			(end -0.12065 -0.3048)
			(stroke
				(width 0.1)
				(type default)
			)
			(layer "B.Fab")
		)
		(fp_line
			(start 0.12065 -0.2794)
			(end -0.12065 -0.2794)
			(stroke
				(width 0.1)
				(type default)
			)
			(layer "B.Fab")
		)
		(fp_line
			(start -0.67945 -0.3048)
			(end -0.67945 0.3048)
			(stroke
				(width 0.1)
				(type default)
			)
			(layer "B.Fab")
		)
		(fp_line
			(start -0.12065 -0.3048)
			(end -0.67945 -0.3048)
			(stroke
				(width 0.1)
				(type default)
			)
			(layer "B.Fab")
		)
		(fp_line
			(start 0.12065 -0.305054)
			(end 0.12065 -0.2794)
			(stroke
				(width 0.1)
				(type default)
			)
			(layer "B.Fab")
		)
		(fp_line
			(start 0.67945 -0.305054)
			(end 0.12065 -0.305054)
			(stroke
				(width 0.1)
				(type default)
			)
			(layer "B.Fab")
		)
		(pad "1" smd circle
			(at 0.40005 0 90)
			(size 0 0)
			(layers "B.Cu" "B.Mask" "B.Paste")
			(net "P1V05_PCH_AUX")
		)
		(pad "2" smd circle
			(at -0.40005 0 90)
			(size 0 0)
			(layers "B.Cu" "B.Mask" "B.Paste")
			(net "GND")
		)
	)
	(footprint ""
		(layer "B.Cu")
		(at 166.301166 -247.250712 180)
		(property "Reference" "R1270"
			(at 0 0 0)
			(layer "B.SilkS")
			(hide yes)
			(effects
				(font
					(size 1.27 1.27)
				)
				(justify mirror)
			)
		)
		(property "Value" ""
			(at 0 0 0)
			(layer "B.Fab")
			(effects
				(font
					(size 1.27 1.27)
				)
				(justify mirror)
			)
		)
		(duplicate_pad_numbers_are_jumpers no)
		(fp_line
			(start 0.7874 0.4064)
			(end 0.7874 -0.4064)
			(stroke
				(width 0.1524)
				(type default)
			)
			(layer "B.SilkS")
		)
		(fp_line
			(start 0.7874 -0.4064)
			(end -0.7874 -0.4064)
			(stroke
				(width 0.1524)
				(type default)
			)
			(layer "B.SilkS")
		)
		(fp_line
			(start -0.7874 0.4064)
			(end 0.7874 0.4064)
			(stroke
				(width 0.1524)
				(type default)
			)
			(layer "B.SilkS")
		)
		(fp_line
			(start -0.7874 -0.4064)
			(end -0.7874 0.4064)
			(stroke
				(width 0.1524)
				(type default)
			)
			(layer "B.SilkS")
		)
		(fp_line
			(start 0.67945 0.3048)
			(end 0.67945 -0.305054)
			(stroke
				(width 0.1)
				(type default)
			)
			(layer "B.Fab")
		)
		(fp_line
			(start 0.67945 -0.305054)
			(end 0.12065 -0.305054)
			(stroke
				(width 0.1)
				(type default)
			)
			(layer "B.Fab")
		)
		(fp_line
			(start 0.12065 0.3048)
			(end 0.67945 0.3048)
			(stroke
				(width 0.1)
				(type default)
			)
			(layer "B.Fab")
		)
		(fp_line
			(start 0.12065 0.2794)
			(end 0.12065 0.3048)
			(stroke
				(width 0.1)
				(type default)
			)
			(layer "B.Fab")
		)
		(fp_line
			(start 0.12065 -0.2794)
			(end -0.12065 -0.2794)
			(stroke
				(width 0.1)
				(type default)
			)
			(layer "B.Fab")
		)
		(fp_line
			(start 0.12065 -0.305054)
			(end 0.12065 -0.2794)
			(stroke
				(width 0.1)
				(type default)
			)
			(layer "B.Fab")
		)
		(fp_line
			(start -0.120396 0.3048)
			(end -0.120396 0.2794)
			(stroke
				(width 0.1)
				(type default)
			)
			(layer "B.Fab")
		)
		(fp_line
			(start -0.120396 0.2794)
			(end 0.12065 0.2794)
			(stroke
				(width 0.1)
				(type default)
			)
			(layer "B.Fab")
		)
		(fp_line
			(start -0.12065 -0.2794)
			(end -0.12065 -0.3048)
			(stroke
				(width 0.1)
				(type default)
			)
			(layer "B.Fab")
		)
		(fp_line
			(start -0.12065 -0.3048)
			(end -0.67945 -0.3048)
			(stroke
				(width 0.1)
				(type default)
			)
			(layer "B.Fab")
		)
		(fp_line
			(start -0.67945 0.3048)
			(end -0.120396 0.3048)
			(stroke
				(width 0.1)
				(type default)
			)
			(layer "B.Fab")
		)
		(fp_line
			(start -0.67945 -0.3048)
			(end -0.67945 0.3048)
			(stroke
				(width 0.1)
				(type default)
			)
			(layer "B.Fab")
		)
		(pad "1" smd circle
			(at 0.40005 0)
			(size 0 0)
			(layers "B.Cu" "B.Mask" "B.Paste")
			(net "PD_CPU1_PROCDIS_COD_GTL_N")
		)
		(pad "2" smd circle
			(at -0.40005 0)
			(size 0 0)
			(layers "B.Cu" "B.Mask" "B.Paste")
			(net "GND")
		)
	)
	(footprint ""
		(layer "B.Cu")
		(at 124.736098 -333.73568 90)
		(property "Reference" "PC535_P1_4"
			(at 0 0 90)
			(layer "B.SilkS")
			(hide yes)
			(effects
				(font
					(size 1.27 1.27)
				)
				(justify mirror)
			)
		)
		(property "Value" ""
			(at 0 0 90)
			(layer "B.Fab")
			(effects
				(font
					(size 1.27 1.27)
				)
				(justify mirror)
			)
		)
		(duplicate_pad_numbers_are_jumpers no)
		(fp_line
			(start 1.524 -0.762)
			(end -1.524 -0.762)
			(stroke
				(width 0.1524)
				(type default)
			)
			(layer "B.SilkS")
		)
		(fp_line
			(start -1.524 -0.762)
			(end -1.524 0.762)
			(stroke
				(width 0.1524)
				(type default)
			)
			(layer "B.SilkS")
		)
		(fp_line
			(start 1.524 0.762)
			(end 1.524 -0.762)
			(stroke
				(width 0.1524)
				(type default)
			)
			(layer "B.SilkS")
		)
		(fp_line
			(start -1.524 0.762)
			(end 1.524 0.762)
			(stroke
				(width 0.1524)
				(type default)
			)
			(layer "B.SilkS")
		)
		(fp_line
			(start 1.1049 -0.724916)
			(end 1.1049 0.724916)
			(stroke
				(width 0.1)
				(type default)
			)
			(layer "B.Fab")
		)
		(fp_line
			(start -1.1049 -0.724916)
			(end 1.1049 -0.724916)
			(stroke
				(width 0.1)
				(type default)
			)
			(layer "B.Fab")
		)
		(fp_line
			(start 1.1049 0.724916)
			(end -1.1049 0.724916)
			(stroke
				(width 0.1)
				(type default)
			)
			(layer "B.Fab")
		)
		(fp_line
			(start -1.1049 0.724916)
			(end -1.1049 -0.724916)
			(stroke
				(width 0.1)
				(type default)
			)
			(layer "B.Fab")
		)
		(pad "1" smd rect
			(at 0.889 0 90)
			(size 1.016 1.27)
			(layers "B.Cu" "B.Mask" "B.Paste")
			(net "SW_P12V_PVCCIN_CPU1_FLT")
		)
		(pad "2" smd rect
			(at -0.889 0 90)
			(size 1.016 1.27)
			(layers "B.Cu" "B.Mask" "B.Paste")
			(net "GND")
		)
	)
	(footprint ""
		(layer "B.Cu")
		(at 232.283 -423.0116 -90)
		(property "Reference" "R4721"
			(at 0 0 90)
			(layer "B.SilkS")
			(hide yes)
			(effects
				(font
					(size 1.27 1.27)
				)
				(justify mirror)
			)
		)
		(property "Value" ""
			(at 0 0 90)
			(layer "B.Fab")
			(effects
				(font
					(size 1.27 1.27)
				)
				(justify mirror)
			)
		)
		(duplicate_pad_numbers_are_jumpers no)
		(fp_line
			(start -0.7874 0.4064)
			(end 0.7874 0.4064)
			(stroke
				(width 0.1524)
				(type default)
			)
			(layer "B.SilkS")
		)
		(fp_line
			(start 0.7874 0.4064)
			(end 0.7874 -0.4064)
			(stroke
				(width 0.1524)
				(type default)
			)
			(layer "B.SilkS")
		)
		(fp_line
			(start -0.7874 -0.4064)
			(end -0.7874 0.4064)
			(stroke
				(width 0.1524)
				(type default)
			)
			(layer "B.SilkS")
		)
		(fp_line
			(start 0.7874 -0.4064)
			(end -0.7874 -0.4064)
			(stroke
				(width 0.1524)
				(type default)
			)
			(layer "B.SilkS")
		)
		(fp_line
			(start -0.67945 0.3048)
			(end -0.120396 0.3048)
			(stroke
				(width 0.1)
				(type default)
			)
			(layer "B.Fab")
		)
		(fp_line
			(start -0.120396 0.3048)
			(end -0.120396 0.2794)
			(stroke
				(width 0.1)
				(type default)
			)
			(layer "B.Fab")
		)
		(fp_line
			(start 0.12065 0.3048)
			(end 0.67945 0.3048)
			(stroke
				(width 0.1)
				(type default)
			)
			(layer "B.Fab")
		)
		(fp_line
			(start 0.67945 0.3048)
			(end 0.67945 -0.305054)
			(stroke
				(width 0.1)
				(type default)
			)
			(layer "B.Fab")
		)
		(fp_line
			(start -0.120396 0.2794)
			(end 0.12065 0.2794)
			(stroke
				(width 0.1)
				(type default)
			)
			(layer "B.Fab")
		)
		(fp_line
			(start 0.12065 0.2794)
			(end 0.12065 0.3048)
			(stroke
				(width 0.1)
				(type default)
			)
			(layer "B.Fab")
		)
		(fp_line
			(start -0.12065 -0.2794)
			(end -0.12065 -0.3048)
			(stroke
				(width 0.1)
				(type default)
			)
			(layer "B.Fab")
		)
		(fp_line
			(start 0.12065 -0.2794)
			(end -0.12065 -0.2794)
			(stroke
				(width 0.1)
				(type default)
			)
			(layer "B.Fab")
		)
		(fp_line
			(start -0.67945 -0.3048)
			(end -0.67945 0.3048)
			(stroke
				(width 0.1)
				(type default)
			)
			(layer "B.Fab")
		)
		(fp_line
			(start -0.12065 -0.3048)
			(end -0.67945 -0.3048)
			(stroke
				(width 0.1)
				(type default)
			)
			(layer "B.Fab")
		)
		(fp_line
			(start 0.12065 -0.305054)
			(end 0.12065 -0.2794)
			(stroke
				(width 0.1)
				(type default)
			)
			(layer "B.Fab")
		)
		(fp_line
			(start 0.67945 -0.305054)
			(end 0.12065 -0.305054)
			(stroke
				(width 0.1)
				(type default)
			)
			(layer "B.Fab")
		)
		(pad "1" smd circle
			(at 0.40005 0 90)
			(size 0 0)
			(layers "B.Cu" "B.Mask" "B.Paste")
			(net "FM_AC_PWR_BTN_R_N")
		)
		(pad "2" smd circle
			(at -0.40005 0 90)
			(size 0 0)
			(layers "B.Cu" "B.Mask" "B.Paste")
			(net "FM_AC_PWR_BTN_PDB_N")
		)
	)
	(footprint ""
		(layer "B.Cu")
		(at 236.67593 -49.120044)
		(property "Reference" "C1282"
			(at 0 0 0)
			(layer "B.SilkS")
			(hide yes)
			(effects
				(font
					(size 1.27 1.27)
				)
				(justify mirror)
			)
		)
		(property "Value" ""
			(at 0 0 0)
			(layer "B.Fab")
			(effects
				(font
					(size 1.27 1.27)
				)
				(justify mirror)
			)
		)
		(duplicate_pad_numbers_are_jumpers no)
		(fp_line
			(start -0.7874 -0.4064)
			(end -0.7874 0.4064)
			(stroke
				(width 0.1524)
				(type default)
			)
			(layer "B.SilkS")
		)
		(fp_line
			(start -0.7874 0.4064)
			(end 0.7874 0.4064)
			(stroke
				(width 0.1524)
				(type default)
			)
			(layer "B.SilkS")
		)
		(fp_line
			(start 0.7874 -0.4064)
			(end -0.7874 -0.4064)
			(stroke
				(width 0.1524)
				(type default)
			)
			(layer "B.SilkS")
		)
		(fp_line
			(start 0.7874 0.4064)
			(end 0.7874 -0.4064)
			(stroke
				(width 0.1524)
				(type default)
			)
			(layer "B.SilkS")
		)
		(fp_line
			(start -0.67945 -0.3048)
			(end -0.67945 0.3048)
			(stroke
				(width 0.1)
				(type default)
			)
			(layer "B.Fab")
		)
		(fp_line
			(start -0.67945 0.3048)
			(end -0.120396 0.3048)
			(stroke
				(width 0.1)
				(type default)
			)
			(layer "B.Fab")
		)
		(fp_line
			(start -0.12065 -0.3048)
			(end -0.67945 -0.3048)
			(stroke
				(width 0.1)
				(type default)
			)
			(layer "B.Fab")
		)
		(fp_line
			(start -0.12065 -0.2794)
			(end -0.12065 -0.3048)
			(stroke
				(width 0.1)
				(type default)
			)
			(layer "B.Fab")
		)
		(fp_line
			(start -0.120396 0.2794)
			(end 0.12065 0.2794)
			(stroke
				(width 0.1)
				(type default)
			)
			(layer "B.Fab")
		)
		(fp_line
			(start -0.120396 0.3048)
			(end -0.120396 0.2794)
			(stroke
				(width 0.1)
				(type default)
			)
			(layer "B.Fab")
		)
		(fp_line
			(start 0.12065 -0.305054)
			(end 0.12065 -0.2794)
			(stroke
				(width 0.1)
				(type default)
			)
			(layer "B.Fab")
		)
		(fp_line
			(start 0.12065 -0.2794)
			(end -0.12065 -0.2794)
			(stroke
				(width 0.1)
				(type default)
			)
			(layer "B.Fab")
		)
		(fp_line
			(start 0.12065 0.2794)
			(end 0.12065 0.3048)
			(stroke
				(width 0.1)
				(type default)
			)
			(layer "B.Fab")
		)
		(fp_line
			(start 0.12065 0.3048)
			(end 0.67945 0.3048)
			(stroke
				(width 0.1)
				(type default)
			)
			(layer "B.Fab")
		)
		(fp_line
			(start 0.67945 -0.305054)
			(end 0.12065 -0.305054)
			(stroke
				(width 0.1)
				(type default)
			)
			(layer "B.Fab")
		)
		(fp_line
			(start 0.67945 0.3048)
			(end 0.67945 -0.305054)
			(stroke
				(width 0.1)
				(type default)
			)
			(layer "B.Fab")
		)
		(pad "1" smd circle
			(at 0.40005 0 180)
			(size 0 0)
			(layers "B.Cu" "B.Mask" "B.Paste")
			(net "P3V3_E1S_0")
		)
		(pad "2" smd circle
			(at -0.40005 0 180)
			(size 0 0)
			(layers "B.Cu" "B.Mask" "B.Paste")
			(net "GND")
		)
	)
	(footprint ""
		(layer "B.Cu")
		(at 209.794856 -194.136264)
		(property "Reference" "C540"
			(at 0 0 0)
			(layer "B.SilkS")
			(hide yes)
			(effects
				(font
					(size 1.27 1.27)
				)
				(justify mirror)
			)
		)
		(property "Value" ""
			(at 0 0 0)
			(layer "B.Fab")
			(effects
				(font
					(size 1.27 1.27)
				)
				(justify mirror)
			)
		)
		(duplicate_pad_numbers_are_jumpers no)
		(fp_line
			(start -0.7874 -0.4064)
			(end -0.7874 0.4064)
			(stroke
				(width 0.1524)
				(type default)
			)
			(layer "B.SilkS")
		)
		(fp_line
			(start -0.7874 0.4064)
			(end 0.7874 0.4064)
			(stroke
				(width 0.1524)
				(type default)
			)
			(layer "B.SilkS")
		)
		(fp_line
			(start 0.7874 -0.4064)
			(end -0.7874 -0.4064)
			(stroke
				(width 0.1524)
				(type default)
			)
			(layer "B.SilkS")
		)
		(fp_line
			(start 0.7874 0.4064)
			(end 0.7874 -0.4064)
			(stroke
				(width 0.1524)
				(type default)
			)
			(layer "B.SilkS")
		)
		(fp_line
			(start -0.67945 -0.3048)
			(end -0.67945 0.3048)
			(stroke
				(width 0.1)
				(type default)
			)
			(layer "B.Fab")
		)
		(fp_line
			(start -0.67945 0.3048)
			(end -0.120396 0.3048)
			(stroke
				(width 0.1)
				(type default)
			)
			(layer "B.Fab")
		)
		(fp_line
			(start -0.12065 -0.3048)
			(end -0.67945 -0.3048)
			(stroke
				(width 0.1)
				(type default)
			)
			(layer "B.Fab")
		)
		(fp_line
			(start -0.12065 -0.2794)
			(end -0.12065 -0.3048)
			(stroke
				(width 0.1)
				(type default)
			)
			(layer "B.Fab")
		)
		(fp_line
			(start -0.120396 0.2794)
			(end 0.12065 0.2794)
			(stroke
				(width 0.1)
				(type default)
			)
			(layer "B.Fab")
		)
		(fp_line
			(start -0.120396 0.3048)
			(end -0.120396 0.2794)
			(stroke
				(width 0.1)
				(type default)
			)
			(layer "B.Fab")
		)
		(fp_line
			(start 0.12065 -0.305054)
			(end 0.12065 -0.2794)
			(stroke
				(width 0.1)
				(type default)
			)
			(layer "B.Fab")
		)
		(fp_line
			(start 0.12065 -0.2794)
			(end -0.12065 -0.2794)
			(stroke
				(width 0.1)
				(type default)
			)
			(layer "B.Fab")
		)
		(fp_line
			(start 0.12065 0.2794)
			(end 0.12065 0.3048)
			(stroke
				(width 0.1)
				(type default)
			)
			(layer "B.Fab")
		)
		(fp_line
			(start 0.12065 0.3048)
			(end 0.67945 0.3048)
			(stroke
				(width 0.1)
				(type default)
			)
			(layer "B.Fab")
		)
		(fp_line
			(start 0.67945 -0.305054)
			(end 0.12065 -0.305054)
			(stroke
				(width 0.1)
				(type default)
			)
			(layer "B.Fab")
		)
		(fp_line
			(start 0.67945 0.3048)
			(end 0.67945 -0.305054)
			(stroke
				(width 0.1)
				(type default)
			)
			(layer "B.Fab")
		)
		(pad "1" smd circle
			(at 0.40005 0 180)
			(size 0 0)
			(layers "B.Cu" "B.Mask" "B.Paste")
			(net "P3V3_AUX")
		)
		(pad "2" smd circle
			(at -0.40005 0 180)
			(size 0 0)
			(layers "B.Cu" "B.Mask" "B.Paste")
			(net "GND")
		)
	)
	(footprint ""
		(layer "B.Cu")
		(at 329.367388 -333.62138 -90)
		(property "Reference" "PC245_P0_7"
			(at 0 0 90)
			(layer "B.SilkS")
			(hide yes)
			(effects
				(font
					(size 1.27 1.27)
				)
				(justify mirror)
			)
		)
		(property "Value" ""
			(at 0 0 90)
			(layer "B.Fab")
			(effects
				(font
					(size 1.27 1.27)
				)
				(justify mirror)
			)
		)
		(duplicate_pad_numbers_are_jumpers no)
		(fp_line
			(start -1.524 0.762)
			(end 1.524 0.762)
			(stroke
				(width 0.1524)
				(type default)
			)
			(layer "B.SilkS")
		)
		(fp_line
			(start 1.524 0.762)
			(end 1.524 -0.762)
			(stroke
				(width 0.1524)
				(type default)
			)
			(layer "B.SilkS")
		)
		(fp_line
			(start -1.524 -0.762)
			(end -1.524 0.762)
			(stroke
				(width 0.1524)
				(type default)
			)
			(layer "B.SilkS")
		)
		(fp_line
			(start 1.524 -0.762)
			(end -1.524 -0.762)
			(stroke
				(width 0.1524)
				(type default)
			)
			(layer "B.SilkS")
		)
		(fp_line
			(start -1.1049 0.724916)
			(end -1.1049 -0.724916)
			(stroke
				(width 0.1)
				(type default)
			)
			(layer "B.Fab")
		)
		(fp_line
			(start 1.1049 0.724916)
			(end -1.1049 0.724916)
			(stroke
				(width 0.1)
				(type default)
			)
			(layer "B.Fab")
		)
		(fp_line
			(start -1.1049 -0.724916)
			(end 1.1049 -0.724916)
			(stroke
				(width 0.1)
				(type default)
			)
			(layer "B.Fab")
		)
		(fp_line
			(start 1.1049 -0.724916)
			(end 1.1049 0.724916)
			(stroke
				(width 0.1)
				(type default)
			)
			(layer "B.Fab")
		)
		(pad "1" smd rect
			(at 0.889 0 270)
			(size 1.016 1.27)
			(layers "B.Cu" "B.Mask" "B.Paste")
			(net "PVCCIN_CPU0")
		)
		(pad "2" smd rect
			(at -0.889 0 270)
			(size 1.016 1.27)
			(layers "B.Cu" "B.Mask" "B.Paste")
			(net "GND")
		)
	)
)
